(kicad_pcb
	(version 20241229)
	(generator "pcbnew")
	(generator_version "9.0")
	(general
		(thickness 1.62)
		(legacy_teardrops no)
	)
	(paper "A3")
	(title_block
		(title "COM Express 7 Baseboard")
		(date "2025-02-04")
		(rev "1.1.2")
		(company "Antmicro Ltd")
		(comment 1 "www.antmicro.com")
		(comment 9 "footprints 204-208 of 802")
	)
	(layers
		(0 "F.Cu" signal)
		(4 "In1.Cu" signal)
		(6 "In2.Cu" signal)
		(8 "In3.Cu" signal)
		(10 "In4.Cu" signal)
		(12 "In5.Cu" signal)
		(14 "In6.Cu" signal)
		(2 "B.Cu" signal)
		(9 "F.Adhes" user "F.Adhesive")
		(11 "B.Adhes" user "B.Adhesive")
		(13 "F.Paste" user)
		(15 "B.Paste" user)
		(5 "F.SilkS" user "F.Silkscreen")
		(7 "B.SilkS" user "B.Silkscreen")
		(1 "F.Mask" user)
		(3 "B.Mask" user)
		(17 "Dwgs.User" user "User.Drawings")
		(19 "Cmts.User" user "User.Comments")
		(21 "Eco1.User" user "User.Eco1")
		(23 "Eco2.User" user "User.Eco2")
		(25 "Edge.Cuts" user)
		(27 "Margin" user)
		(31 "F.CrtYd" user "F.Courtyard")
		(29 "B.CrtYd" user "B.Courtyard")
		(35 "F.Fab" user)
		(33 "B.Fab" user)
	)
	(footprint "antmicro-footprints:R_0402_1005Metric"
		(layer "F.Cu")
		(at 124.4 75.81 -90)
		(descr "Resistor SMD 0402")
		(tags "resistor SMD 0402")
		(property "Reference" "R74"
			(at -3 -0.45 90)
			(layer "F.SilkS")
			(effects
				(font
					(size 0.7 0.7)
					(thickness 0.15)
				)
				(justify right bottom)
			)
		)
		(property "Value" "R_0R_0402"
			(at -1.011843 1.772047 90)
			(layer "F.Fab")
			(effects
				(font
					(size 0.7 0.7)
					(thickness 0.15)
				)
				(justify right bottom)
			)
		)
		(property "Datasheet" "https://industrial.panasonic.com/cdbs/www-data/pdf/RDA0000/AOA0000C301.pdf"
			(at 0 0 270)
			(layer "F.Fab")
			(hide yes)
			(effects
				(font
					(size 1.27 1.27)
					(thickness 0.15)
				)
			)
		)
		(property "Author" "Antmicro"
			(at 48.59 200.21 0)
			(layer "F.Fab")
			(hide yes)
			(effects
				(font
					(size 1 1)
					(thickness 0.15)
				)
			)
		)
		(property "Current" "1A"
			(at 48.59 200.21 0)
			(layer "F.Fab")
			(hide yes)
			(effects
				(font
					(size 1 1)
					(thickness 0.15)
				)
			)
		)
		(property "License" "Apache-2.0"
			(at 48.59 200.21 0)
			(layer "F.Fab")
			(hide yes)
			(effects
				(font
					(size 1 1)
					(thickness 0.15)
				)
			)
		)
		(property "MPN" "ERJ2GE0R00X"
			(at 48.59 200.21 0)
			(layer "F.Fab")
			(hide yes)
			(effects
				(font
					(size 1 1)
					(thickness 0.15)
				)
			)
		)
		(property "Manufacturer" "Panasonic"
			(at 48.59 200.21 0)
			(layer "F.Fab")
			(hide yes)
			(effects
				(font
					(size 1 1)
					(thickness 0.15)
				)
			)
		)
		(property "Public" "False"
			(at 48.59 200.21 0)
			(layer "F.Fab")
			(hide yes)
			(effects
				(font
					(size 1 1)
					(thickness 0.15)
				)
			)
		)
		(property "Tolerance" ""
			(at 48.59 200.21 0)
			(layer "F.Fab")
			(hide yes)
			(effects
				(font
					(size 1 1)
					(thickness 0.15)
				)
			)
		)
		(property "Val" "0R"
			(at 48.59 200.21 0)
			(layer "F.Fab")
			(hide yes)
			(effects
				(font
					(size 1 1)
					(thickness 0.15)
				)
			)
		)
		(sheetname "USB-C console")
		(sheetfile "usb-c_console.kicad_sch")
		(attr smd)
		(fp_rect
			(start -0.925 -0.47)
			(end 0.925 0.47)
			(stroke
				(width 0.05)
				(type default)
			)
			(fill no)
			(layer "F.CrtYd")
		)
		(fp_rect
			(start -0.5 -0.25)
			(end 0.5 0.25)
			(stroke
				(width 0.15)
				(type solid)
			)
			(fill no)
			(layer "F.Fab")
		)
		(pad "1" smd roundrect
			(at -0.48 0 270)
			(size 0.59 0.64)
			(layers "F.Cu" "F.Mask" "F.Paste")
			(roundrect_rratio 0.25)
			(net 571 "Net-(U7-A_{1})")
			(pintype "passive")
			(teardrops
				(best_length_ratio 0.2)
				(max_length 1)
				(best_width_ratio 0.9)
				(max_width 2)
				(curved_edges yes)
				(filter_ratio 0.9)
				(enabled yes)
				(allow_two_segments yes)
				(prefer_zone_connections yes)
			)
		)
		(pad "2" smd roundrect
			(at 0.48 0 270)
			(size 0.59 0.64)
			(layers "F.Cu" "F.Mask" "F.Paste")
			(roundrect_rratio 0.25)
			(net 344 "/Com Express 7 MGMT/SER0.TX")
			(pintype "passive")
			(teardrops
				(best_length_ratio 0.2)
				(max_length 1)
				(best_width_ratio 0.9)
				(max_width 2)
				(curved_edges yes)
				(filter_ratio 0.9)
				(enabled yes)
				(allow_two_segments yes)
				(prefer_zone_connections yes)
			)
		)
	)
	(footprint "antmicro-footprints:C_0402_1005Metric"
		(layer "F.Cu")
		(at 304.14 126.79)
		(descr "Capacitor SMD 0402")
		(tags "capacitor SMD 0402")
		(property "Reference" "C55"
			(at 0.86 0.42 0)
			(layer "F.SilkS")
			(effects
				(font
					(size 0.7 0.7)
					(thickness 0.15)
				)
				(justify left bottom)
			)
		)
		(property "Value" "C_100n_0402"
			(at -1.022927 2.155213 0)
			(layer "F.Fab")
			(effects
				(font
					(size 0.7 0.7)
					(thickness 0.15)
				)
				(justify left bottom)
			)
		)
		(property "Datasheet" "https://www.murata.com/products/productdetail?partno=GRM155R61H104KE14%23"
			(at 0 0 0)
			(layer "F.Fab")
			(hide yes)
			(effects
				(font
					(size 1.27 1.27)
					(thickness 0.15)
				)
			)
		)
		(property "Author" "Antmicro"
			(at 0 0 0)
			(layer "F.Fab")
			(hide yes)
			(effects
				(font
					(size 1 1)
					(thickness 0.15)
				)
			)
		)
		(property "Dielectric" "X5R"
			(at 0 0 0)
			(layer "F.Fab")
			(hide yes)
			(effects
				(font
					(size 1 1)
					(thickness 0.15)
				)
			)
		)
		(property "License" "Apache-2.0"
			(at 0 0 0)
			(layer "F.Fab")
			(hide yes)
			(effects
				(font
					(size 1 1)
					(thickness 0.15)
				)
			)
		)
		(property "MPN" "GRM155R61H104KE14D"
			(at 0 0 0)
			(layer "F.Fab")
			(hide yes)
			(effects
				(font
					(size 1 1)
					(thickness 0.15)
				)
			)
		)
		(property "Manufacturer" "Murata"
			(at 0 0 0)
			(layer "F.Fab")
			(hide yes)
			(effects
				(font
					(size 1 1)
					(thickness 0.15)
				)
			)
		)
		(property "Public" "False"
			(at 0 0 0)
			(layer "F.Fab")
			(hide yes)
			(effects
				(font
					(size 1 1)
					(thickness 0.15)
				)
			)
		)
		(property "Val" "100n"
			(at 0 0 0)
			(layer "F.Fab")
			(hide yes)
			(effects
				(font
					(size 1 1)
					(thickness 0.15)
				)
			)
		)
		(property "Voltage" "50V"
			(at 0 0 0)
			(layer "F.Fab")
			(hide yes)
			(effects
				(font
					(size 1 1)
					(thickness 0.15)
				)
			)
		)
		(sheetname "Power")
		(sheetfile "power.kicad_sch")
		(attr smd)
		(fp_rect
			(start -0.925 -0.47)
			(end 0.925 0.47)
			(stroke
				(width 0.05)
				(type default)
			)
			(fill no)
			(layer "F.CrtYd")
		)
		(fp_line
			(start -0.494 -0.25)
			(end 0.504 -0.25)
			(stroke
				(width 0.15)
				(type solid)
			)
			(layer "F.Fab")
		)
		(fp_line
			(start -0.494 0.248)
			(end -0.494 -0.25)
			(stroke
				(width 0.15)
				(type solid)
			)
			(layer "F.Fab")
		)
		(fp_line
			(start 0.504 -0.25)
			(end 0.504 0.248)
			(stroke
				(width 0.15)
				(type solid)
			)
			(layer "F.Fab")
		)
		(fp_line
			(start 0.504 0.248)
			(end -0.494 0.248)
			(stroke
				(width 0.15)
				(type solid)
			)
			(layer "F.Fab")
		)
		(pad "1" smd roundrect
			(at -0.48 0)
			(size 0.59 0.64)
			(layers "F.Cu" "F.Mask" "F.Paste")
			(roundrect_rratio 0.25)
			(net 1 "GND")
			(pintype "passive")
			(teardrops
				(best_length_ratio 0.2)
				(max_length 1)
				(best_width_ratio 0.9)
				(max_width 2)
				(curved_edges yes)
				(filter_ratio 0.9)
				(enabled yes)
				(allow_two_segments yes)
				(prefer_zone_connections yes)
			)
		)
		(pad "2" smd roundrect
			(at 0.48 0)
			(size 0.59 0.64)
			(layers "F.Cu" "F.Mask" "F.Paste")
			(roundrect_rratio 0.25)
			(net 72 "Net-(U20-CT)")
			(pintype "passive")
			(teardrops
				(best_length_ratio 0.2)
				(max_length 1)
				(best_width_ratio 0.9)
				(max_width 2)
				(curved_edges yes)
				(filter_ratio 0.9)
				(enabled yes)
				(allow_two_segments yes)
				(prefer_zone_connections yes)
			)
		)
	)
	(footprint "antmicro-footprints:C_0402_1005Metric"
		(layer "F.Cu")
		(at 310.175 82.8 -90)
		(descr "Capacitor SMD 0402")
		(tags "capacitor SMD 0402")
		(property "Reference" "C110"
			(at -1.34 -1.325 90)
			(layer "F.SilkS")
			(effects
				(font
					(size 0.7 0.7)
					(thickness 0.15)
				)
				(justify right bottom)
			)
		)
		(property "Value" "C_100n_0402"
			(at -1.022927 2.155213 90)
			(layer "F.Fab")
			(effects
				(font
					(size 0.7 0.7)
					(thickness 0.15)
				)
				(justify right bottom)
			)
		)
		(property "Datasheet" "https://www.murata.com/products/productdetail?partno=GRM155R61H104KE14%23"
			(at 0 0 270)
			(layer "F.Fab")
			(hide yes)
			(effects
				(font
					(size 1.27 1.27)
					(thickness 0.15)
				)
			)
		)
		(property "Author" "Antmicro"
			(at 227.375 392.975 0)
			(layer "F.Fab")
			(hide yes)
			(effects
				(font
					(size 1 1)
					(thickness 0.15)
				)
			)
		)
		(property "Dielectric" "X5R"
			(at 227.375 392.975 0)
			(layer "F.Fab")
			(hide yes)
			(effects
				(font
					(size 1 1)
					(thickness 0.15)
				)
			)
		)
		(property "License" "Apache-2.0"
			(at 227.375 392.975 0)
			(layer "F.Fab")
			(hide yes)
			(effects
				(font
					(size 1 1)
					(thickness 0.15)
				)
			)
		)
		(property "MPN" "GRM155R61H104KE14D"
			(at 227.375 392.975 0)
			(layer "F.Fab")
			(hide yes)
			(effects
				(font
					(size 1 1)
					(thickness 0.15)
				)
			)
		)
		(property "Manufacturer" "Murata"
			(at 227.375 392.975 0)
			(layer "F.Fab")
			(hide yes)
			(effects
				(font
					(size 1 1)
					(thickness 0.15)
				)
			)
		)
		(property "Public" "False"
			(at 227.375 392.975 0)
			(layer "F.Fab")
			(hide yes)
			(effects
				(font
					(size 1 1)
					(thickness 0.15)
				)
			)
		)
		(property "Val" "100n"
			(at 227.375 392.975 0)
			(layer "F.Fab")
			(hide yes)
			(effects
				(font
					(size 1 1)
					(thickness 0.15)
				)
			)
		)
		(property "Voltage" "50V"
			(at 227.375 392.975 0)
			(layer "F.Fab")
			(hide yes)
			(effects
				(font
					(size 1 1)
					(thickness 0.15)
				)
			)
		)
		(sheetname "PCIe misc")
		(sheetfile "pcie_misc.kicad_sch")
		(attr smd)
		(fp_rect
			(start -0.925 -0.47)
			(end 0.925 0.47)
			(stroke
				(width 0.05)
				(type default)
			)
			(fill no)
			(layer "F.CrtYd")
		)
		(fp_line
			(start -0.494 0.248)
			(end -0.494 -0.25)
			(stroke
				(width 0.15)
				(type solid)
			)
			(layer "F.Fab")
		)
		(fp_line
			(start 0.504 0.248)
			(end -0.494 0.248)
			(stroke
				(width 0.15)
				(type solid)
			)
			(layer "F.Fab")
		)
		(fp_line
			(start -0.494 -0.25)
			(end 0.504 -0.25)
			(stroke
				(width 0.15)
				(type solid)
			)
			(layer "F.Fab")
		)
		(fp_line
			(start 0.504 -0.25)
			(end 0.504 0.248)
			(stroke
				(width 0.15)
				(type solid)
			)
			(layer "F.Fab")
		)
		(pad "1" smd roundrect
			(at -0.48 0 270)
			(size 0.59 0.64)
			(layers "F.Cu" "F.Mask" "F.Paste")
			(roundrect_rratio 0.25)
			(net 1 "GND")
			(pintype "passive")
			(teardrops
				(best_length_ratio 0.2)
				(max_length 1)
				(best_width_ratio 0.9)
				(max_width 2)
				(curved_edges yes)
				(filter_ratio 0.9)
				(enabled yes)
				(allow_two_segments yes)
				(prefer_zone_connections yes)
			)
		)
		(pad "2" smd roundrect
			(at 0.48 0 270)
			(size 0.59 0.64)
			(layers "F.Cu" "F.Mask" "F.Paste")
			(roundrect_rratio 0.25)
			(net 2 "+3V3")
			(pintype "passive")
			(teardrops
				(best_length_ratio 0.2)
				(max_length 1)
				(best_width_ratio 0.9)
				(max_width 2)
				(curved_edges yes)
				(filter_ratio 0.9)
				(enabled yes)
				(allow_two_segments yes)
				(prefer_zone_connections yes)
			)
		)
	)
	(footprint "antmicro-footprints:VSSOP-8_2.3x2mm_P0.5mm"
		(layer "F.Cu")
		(at 308.5 153.81 90)
		(property "Reference" "U30"
			(at -1.05 2.25 90)
			(layer "F.SilkS")
			(effects
				(font
					(size 0.7 0.7)
					(thickness 0.15)
				)
				(justify left bottom)
			)
		)
		(property "Value" "74AUP2G132"
			(at 0 2.258 90)
			(layer "F.Fab")
			(effects
				(font
					(size 0.7 0.7)
					(thickness 0.15)
				)
				(justify left bottom)
			)
		)
		(property "Datasheet" "https://assets.nexperia.com/documents/data-sheet/74AUP2G132.pdf"
			(at 0 0 90)
			(layer "F.Fab")
			(hide yes)
			(effects
				(font
					(size 1.27 1.27)
					(thickness 0.15)
				)
			)
		)
		(property "Author" "Antmicro"
			(at 462.31 -154.69 0)
			(layer "F.Fab")
			(hide yes)
			(effects
				(font
					(size 1 1)
					(thickness 0.15)
				)
			)
		)
		(property "License" "Apache-2.0"
			(at 462.31 -154.69 0)
			(layer "F.Fab")
			(hide yes)
			(effects
				(font
					(size 1 1)
					(thickness 0.15)
				)
			)
		)
		(property "MPN" "74AUP2G132"
			(at 462.31 -154.69 0)
			(layer "F.Fab")
			(hide yes)
			(effects
				(font
					(size 1 1)
					(thickness 0.15)
				)
			)
		)
		(property "Manufacturer" "Nexperia"
			(at 462.31 -154.69 0)
			(layer "F.Fab")
			(hide yes)
			(effects
				(font
					(size 1 1)
					(thickness 0.15)
				)
			)
		)
		(sheetname "Com Express 7 MGMT")
		(sheetfile "com_express_7_mgmt.kicad_sch")
		(attr smd)
		(fp_line
			(start -0.82 -0.992)
			(end 0.825 -0.992)
			(stroke
				(width 0.15)
				(type solid)
			)
			(layer "F.SilkS")
		)
		(fp_line
			(start 0.825 1.007)
			(end -0.82 1.007)
			(stroke
				(width 0.15)
				(type solid)
			)
			(layer "F.SilkS")
		)
		(fp_circle
			(center -1.402 -1.192)
			(end -1.352 -1.192)
			(stroke
				(width 0.15)
				(type solid)
			)
			(fill yes)
			(layer "F.SilkS")
		)
		(fp_rect
			(start 1.8 1.35)
			(end -1.8 -1.35)
			(stroke
				(width 0.05)
				(type solid)
			)
			(fill no)
			(layer "F.CrtYd")
		)
		(fp_line
			(start -0.7 -0.99)
			(end -1.14 -0.55)
			(stroke
				(width 0.15)
				(type solid)
			)
			(layer "F.Fab")
		)
		(fp_rect
			(start -1.147 -0.992)
			(end 1.151 1.007)
			(stroke
				(width 0.15)
				(type solid)
			)
			(fill no)
			(layer "F.Fab")
		)
		(pad "1" smd rect
			(at -1.372 -0.742 90)
			(size 0.75 0.4)
			(layers "F.Cu" "F.Mask" "F.Paste")
			(net 382 "Net-(J12D-~{CB_RESET})")
			(pinfunction "1A")
			(pintype "input")
			(teardrops
				(best_length_ratio 0.2)
				(max_length 1)
				(best_width_ratio 0.9)
				(max_width 2)
				(curved_edges yes)
				(filter_ratio 0.9)
				(enabled yes)
				(allow_two_segments yes)
				(prefer_zone_connections yes)
			)
		)
		(pad "2" smd rect
			(at -1.372 -0.244 90)
			(size 0.75 0.3)
			(layers "F.Cu" "F.Mask" "F.Paste")
			(net 382 "Net-(J12D-~{CB_RESET})")
			(pinfunction "1B")
			(pintype "input")
			(teardrops
				(best_length_ratio 0.2)
				(max_length 1)
				(best_width_ratio 0.9)
				(max_width 2)
				(curved_edges yes)
				(filter_ratio 0.9)
				(enabled yes)
				(allow_two_segments yes)
				(prefer_zone_connections yes)
			)
		)
		(pad "3" smd rect
			(at -1.372 0.256 90)
			(size 0.75 0.3)
			(layers "F.Cu" "F.Mask" "F.Paste")
			(net 528 "/Backplane/~{PERST}")
			(pinfunction "2Y")
			(pintype "output")
			(teardrops
				(best_length_ratio 0.2)
				(max_length 1)
				(best_width_ratio 0.9)
				(max_width 2)
				(curved_edges yes)
				(filter_ratio 0.9)
				(enabled yes)
				(allow_two_segments yes)
				(prefer_zone_connections yes)
			)
		)
		(pad "4" smd rect
			(at -1.372 0.757 90)
			(size 0.75 0.4)
			(layers "F.Cu" "F.Mask" "F.Paste")
			(net 1 "GND")
			(pinfunction "GND")
			(pintype "power_in")
			(teardrops
				(best_length_ratio 0.2)
				(max_length 1)
				(best_width_ratio 0.9)
				(max_width 2)
				(curved_edges yes)
				(filter_ratio 0.9)
				(enabled yes)
				(allow_two_segments yes)
				(prefer_zone_connections yes)
			)
		)
		(pad "5" smd rect
			(at 1.377 0.757 90)
			(size 0.75 0.4)
			(layers "F.Cu" "F.Mask" "F.Paste")
			(net 784 "Net-(U30-1Y)")
			(pinfunction "2A")
			(pintype "input")
			(teardrops
				(best_length_ratio 0.2)
				(max_length 1)
				(best_width_ratio 0.9)
				(max_width 2)
				(curved_edges yes)
				(filter_ratio 0.9)
				(enabled yes)
				(allow_two_segments yes)
				(prefer_zone_connections yes)
			)
		)
		(pad "6" smd rect
			(at 1.377 0.256 90)
			(size 0.75 0.3)
			(layers "F.Cu" "F.Mask" "F.Paste")
			(net 784 "Net-(U30-1Y)")
			(pinfunction "2B")
			(pintype "input")
			(teardrops
				(best_length_ratio 0.2)
				(max_length 1)
				(best_width_ratio 0.9)
				(max_width 2)
				(curved_edges yes)
				(filter_ratio 0.9)
				(enabled yes)
				(allow_two_segments yes)
				(prefer_zone_connections yes)
			)
		)
		(pad "7" smd rect
			(at 1.377 -0.244 90)
			(size 0.75 0.3)
			(layers "F.Cu" "F.Mask" "F.Paste")
			(net 784 "Net-(U30-1Y)")
			(pinfunction "1Y")
			(pintype "output")
			(teardrops
				(best_length_ratio 0.2)
				(max_length 1)
				(best_width_ratio 0.9)
				(max_width 2)
				(curved_edges yes)
				(filter_ratio 0.9)
				(enabled yes)
				(allow_two_segments yes)
				(prefer_zone_connections yes)
			)
		)
		(pad "8" smd rect
			(at 1.377 -0.742 90)
			(size 0.75 0.4)
			(layers "F.Cu" "F.Mask" "F.Paste")
			(net 73 "+3V3_AON")
			(pinfunction "VCC")
			(pintype "power_in")
			(teardrops
				(best_length_ratio 0.2)
				(max_length 1)
				(best_width_ratio 0.9)
				(max_width 2)
				(curved_edges yes)
				(filter_ratio 0.9)
				(enabled yes)
				(allow_two_segments yes)
				(prefer_zone_connections yes)
			)
		)
	)
	(footprint "antmicro-footprints:R_0402_1005Metric"
		(layer "F.Cu")
		(at 188.70861 77.152163 90)
		(descr "Resistor SMD 0402")
		(tags "resistor SMD 0402")
		(property "Reference" "R326"
			(at -1.9 -0.5 90)
			(layer "F.SilkS")
			(effects
				(font
					(size 0.7 0.7)
					(thickness 0.15)
				)
				(justify left bottom)
			)
		)
		(property "Value" "R_470R_0402"
			(at -1.011843 1.772047 90)
			(layer "F.Fab")
			(effects
				(font
					(size 0.7 0.7)
					(thickness 0.15)
				)
				(justify left bottom)
			)
		)
		(property "Datasheet" "https://www.bourns.com/docs/product-datasheets/cr.pdf"
			(at 0 0 90)
			(layer "F.Fab")
			(hide yes)
			(effects
				(font
					(size 1.27 1.27)
					(thickness 0.15)
				)
			)
		)
		(property "Author" "Antmicro"
			(at 265.860773 -111.556447 0)
			(layer "F.Fab")
			(hide yes)
			(effects
				(font
					(size 1 1)
					(thickness 0.15)
				)
			)
		)
		(property "License" "Apache-2.0"
			(at 265.860773 -111.556447 0)
			(layer "F.Fab")
			(hide yes)
			(effects
				(font
					(size 1 1)
					(thickness 0.15)
				)
			)
		)
		(property "MPN" "CR0402-FX-4700GLF"
			(at 265.860773 -111.556447 0)
			(layer "F.Fab")
			(hide yes)
			(effects
				(font
					(size 1 1)
					(thickness 0.15)
				)
			)
		)
		(property "Manufacturer" "Bourns"
			(at 265.860773 -111.556447 0)
			(layer "F.Fab")
			(hide yes)
			(effects
				(font
					(size 1 1)
					(thickness 0.15)
				)
			)
		)
		(property "Tolerance" "1%"
			(at 265.860773 -111.556447 0)
			(layer "F.Fab")
			(hide yes)
			(effects
				(font
					(size 1 1)
					(thickness 0.15)
				)
			)
		)
		(property "Val" "470R"
			(at 265.860773 -111.556447 0)
			(layer "F.Fab")
			(hide yes)
			(effects
				(font
					(size 1 1)
					(thickness 0.15)
				)
			)
		)
		(sheetname "Power")
		(sheetfile "power.kicad_sch")
		(attr smd)
		(fp_rect
			(start -0.925 -0.47)
			(end 0.925 0.47)
			(stroke
				(width 0.05)
				(type default)
			)
			(fill no)
			(layer "F.CrtYd")
		)
		(fp_rect
			(start -0.5 -0.25)
			(end 0.5 0.25)
			(stroke
				(width 0.15)
				(type solid)
			)
			(fill no)
			(layer "F.Fab")
		)
		(pad "1" smd roundrect
			(at -0.48 0 90)
			(size 0.59 0.64)
			(layers "F.Cu" "F.Mask" "F.Paste")
			(roundrect_rratio 0.25)
			(net 1 "GND")
			(pintype "passive")
			(teardrops
				(best_length_ratio 0.2)
				(max_length 1)
				(best_width_ratio 0.9)
				(max_width 2)
				(curved_edges yes)
				(filter_ratio 0.9)
				(enabled yes)
				(allow_two_segments yes)
				(prefer_zone_connections yes)
			)
		)
		(pad "2" smd roundrect
			(at 0.48 0 90)
			(size 0.59 0.64)
			(layers "F.Cu" "F.Mask" "F.Paste")
			(roundrect_rratio 0.25)
			(net 985 "Net-(D33-C)")
			(pintype "passive")
			(teardrops
				(best_length_ratio 0.2)
				(max_length 1)
				(best_width_ratio 0.9)
				(max_width 2)
				(curved_edges yes)
				(filter_ratio 0.9)
				(enabled yes)
				(allow_two_segments yes)
				(prefer_zone_connections yes)
			)
		)
	)
)
